(kicad_pcb
	(version 20260206)
	(generator "pcbnew")
	(generator_version "10.0")
	(general
		(thickness 1.6)
		(legacy_teardrops no)
	)
	(paper "A4")
	(title_block
		(title "04192023_DAF0TMB3IC0_F0TG_MB_C_brd_V02_OCP.brd")
		(comment 1 "Grand Teton / footprints 7519-7526 of 8354")
	)
	(layers
		(0 "F.Cu" signal "TOP")
		(4 "In1.Cu" signal "GND")
		(6 "In2.Cu" signal "IN1")
		(8 "In3.Cu" signal "GND1")
		(10 "In4.Cu" signal "IN2")
		(12 "In5.Cu" signal "GND2")
		(14 "In6.Cu" signal "IN3")
		(16 "In7.Cu" signal "GND3")
		(18 "In8.Cu" signal "VCC")
		(20 "In9.Cu" signal "VCC1")
		(22 "In10.Cu" signal "GND4")
		(24 "In11.Cu" signal "IN4")
		(26 "In12.Cu" signal "GND5")
		(28 "In13.Cu" signal "IN5")
		(30 "In14.Cu" signal "GND6")
		(32 "In15.Cu" signal "IN6")
		(34 "In16.Cu" signal "GND7")
		(2 "B.Cu" signal "BOTTOM")
		(9 "F.Adhes" user "F.Adhesive")
		(11 "B.Adhes" user "B.Adhesive")
		(13 "F.Paste" user "Package Geometry/Pastemask Top")
		(15 "B.Paste" user "Package Geometry/Pastemask Bottom")
		(5 "F.SilkS" user "Ref Des/Silkscreen Top")
		(7 "B.SilkS" user "Ref Des/Silkscreen Bottom")
		(1 "F.Mask" user "Board Geometry/Soldermask Top")
		(3 "B.Mask" user "Board Geometry/Soldermask Bottom")
		(17 "Dwgs.User" user "User.Drawings")
		(19 "Cmts.User" user "User.Comments")
		(21 "Eco1.User" user "User.Eco1")
		(23 "Eco2.User" user "User.Eco2")
		(25 "Edge.Cuts" user "Board Geometry/Outline")
		(27 "Margin" user)
		(31 "F.CrtYd" user "Package Geometry/Place Bound Top")
		(29 "B.CrtYd" user "Package Geometry/Place Bound Bottom")
		(35 "F.Fab" user "Ref Des/Assembly Top")
		(33 "B.Fab" user "Ref Des/Assembly Bottom")
	)
	(footprint ""
		(layer "B.Cu")
		(at 340.845902 -396.393162 -90)
		(property "Reference" "C617"
			(at 0 0 90)
			(layer "B.SilkS")
			(hide yes)
			(effects
				(font
					(size 1.27 1.27)
				)
				(justify mirror)
			)
		)
		(property "Value" ""
			(at 0 0 90)
			(layer "B.Fab")
			(effects
				(font
					(size 1.27 1.27)
				)
				(justify mirror)
			)
		)
		(duplicate_pad_numbers_are_jumpers no)
		(fp_line
			(start -0.299974 0.150114)
			(end 0.299974 0.150114)
			(stroke
				(width 0.1)
				(type default)
			)
			(layer "B.Fab")
		)
		(fp_line
			(start 0.299974 0.150114)
			(end 0.299974 -0.150114)
			(stroke
				(width 0.1)
				(type default)
			)
			(layer "B.Fab")
		)
		(fp_line
			(start -0.299974 -0.150114)
			(end -0.299974 0.150114)
			(stroke
				(width 0.1)
				(type default)
			)
			(layer "B.Fab")
		)
		(fp_line
			(start 0.299974 -0.150114)
			(end -0.299974 -0.150114)
			(stroke
				(width 0.1)
				(type default)
			)
			(layer "B.Fab")
		)
		(pad "1" smd rect
			(at 0.2667 0 90)
			(size 0.3048 0.381)
			(layers "B.Cu" "B.Mask" "B.Paste")
			(net "P0V9_CPU0_RT1_2A_2D")
		)
		(pad "2" smd rect
			(at -0.2667 0 90)
			(size 0.3048 0.381)
			(layers "B.Cu" "B.Mask" "B.Paste")
			(net "GND")
		)
	)
	(footprint ""
		(layer "B.Cu")
		(at 70.172834 -201.672952)
		(property "Reference" "R530"
			(at 0 0 0)
			(layer "B.SilkS")
			(hide yes)
			(effects
				(font
					(size 1.27 1.27)
				)
				(justify mirror)
			)
		)
		(property "Value" ""
			(at 0 0 0)
			(layer "B.Fab")
			(effects
				(font
					(size 1.27 1.27)
				)
				(justify mirror)
			)
		)
		(duplicate_pad_numbers_are_jumpers no)
		(fp_line
			(start -0.7874 -0.4064)
			(end -0.7874 0.4064)
			(stroke
				(width 0.1524)
				(type default)
			)
			(layer "B.SilkS")
		)
		(fp_line
			(start -0.7874 0.4064)
			(end 0.7874 0.4064)
			(stroke
				(width 0.1524)
				(type default)
			)
			(layer "B.SilkS")
		)
		(fp_line
			(start 0.7874 -0.4064)
			(end -0.7874 -0.4064)
			(stroke
				(width 0.1524)
				(type default)
			)
			(layer "B.SilkS")
		)
		(fp_line
			(start 0.7874 0.4064)
			(end 0.7874 -0.4064)
			(stroke
				(width 0.1524)
				(type default)
			)
			(layer "B.SilkS")
		)
		(fp_line
			(start -0.67945 -0.3048)
			(end -0.67945 0.3048)
			(stroke
				(width 0.1)
				(type default)
			)
			(layer "B.Fab")
		)
		(fp_line
			(start -0.67945 0.3048)
			(end -0.120396 0.3048)
			(stroke
				(width 0.1)
				(type default)
			)
			(layer "B.Fab")
		)
		(fp_line
			(start -0.12065 -0.3048)
			(end -0.67945 -0.3048)
			(stroke
				(width 0.1)
				(type default)
			)
			(layer "B.Fab")
		)
		(fp_line
			(start -0.12065 -0.2794)
			(end -0.12065 -0.3048)
			(stroke
				(width 0.1)
				(type default)
			)
			(layer "B.Fab")
		)
		(fp_line
			(start -0.120396 0.2794)
			(end 0.12065 0.2794)
			(stroke
				(width 0.1)
				(type default)
			)
			(layer "B.Fab")
		)
		(fp_line
			(start -0.120396 0.3048)
			(end -0.120396 0.2794)
			(stroke
				(width 0.1)
				(type default)
			)
			(layer "B.Fab")
		)
		(fp_line
			(start 0.12065 -0.305054)
			(end 0.12065 -0.2794)
			(stroke
				(width 0.1)
				(type default)
			)
			(layer "B.Fab")
		)
		(fp_line
			(start 0.12065 -0.2794)
			(end -0.12065 -0.2794)
			(stroke
				(width 0.1)
				(type default)
			)
			(layer "B.Fab")
		)
		(fp_line
			(start 0.12065 0.2794)
			(end 0.12065 0.3048)
			(stroke
				(width 0.1)
				(type default)
			)
			(layer "B.Fab")
		)
		(fp_line
			(start 0.12065 0.3048)
			(end 0.67945 0.3048)
			(stroke
				(width 0.1)
				(type default)
			)
			(layer "B.Fab")
		)
		(fp_line
			(start 0.67945 -0.305054)
			(end 0.12065 -0.305054)
			(stroke
				(width 0.1)
				(type default)
			)
			(layer "B.Fab")
		)
		(fp_line
			(start 0.67945 0.3048)
			(end 0.67945 -0.305054)
			(stroke
				(width 0.1)
				(type default)
			)
			(layer "B.Fab")
		)
		(pad "1" smd circle
			(at 0.40005 0 180)
			(size 0 0)
			(layers "B.Cu" "B.Mask" "B.Paste")
			(net "RST_CPU0_RESETL_N")
		)
		(pad "2" smd circle
			(at -0.40005 0 180)
			(size 0 0)
			(layers "B.Cu" "B.Mask" "B.Paste")
			(net "RST_CPU1_RESETL_N")
		)
	)
	(footprint ""
		(layer "B.Cu")
		(at 148.34616 -388.011162 -90)
		(property "Reference" "C428"
			(at 0 0 90)
			(layer "B.SilkS")
			(hide yes)
			(effects
				(font
					(size 1.27 1.27)
				)
				(justify mirror)
			)
		)
		(property "Value" ""
			(at 0 0 90)
			(layer "B.Fab")
			(effects
				(font
					(size 1.27 1.27)
				)
				(justify mirror)
			)
		)
		(duplicate_pad_numbers_are_jumpers no)
		(fp_line
			(start -0.299974 0.150114)
			(end 0.299974 0.150114)
			(stroke
				(width 0.1)
				(type default)
			)
			(layer "B.Fab")
		)
		(fp_line
			(start 0.299974 0.150114)
			(end 0.299974 -0.150114)
			(stroke
				(width 0.1)
				(type default)
			)
			(layer "B.Fab")
		)
		(fp_line
			(start -0.299974 -0.150114)
			(end -0.299974 0.150114)
			(stroke
				(width 0.1)
				(type default)
			)
			(layer "B.Fab")
		)
		(fp_line
			(start 0.299974 -0.150114)
			(end -0.299974 -0.150114)
			(stroke
				(width 0.1)
				(type default)
			)
			(layer "B.Fab")
		)
		(pad "1" smd rect
			(at 0.2667 0 90)
			(size 0.3048 0.381)
			(layers "B.Cu" "B.Mask" "B.Paste")
			(net "P0V9_CPU1_RT2_2A")
		)
		(pad "2" smd rect
			(at -0.2667 0 90)
			(size 0.3048 0.381)
			(layers "B.Cu" "B.Mask" "B.Paste")
			(net "GND")
		)
	)
	(footprint ""
		(layer "B.Cu")
		(at 406.698958 -326.894952)
		(property "Reference" "R440"
			(at 0 0 0)
			(layer "B.SilkS")
			(hide yes)
			(effects
				(font
					(size 1.27 1.27)
				)
				(justify mirror)
			)
		)
		(property "Value" ""
			(at 0 0 0)
			(layer "B.Fab")
			(effects
				(font
					(size 1.27 1.27)
				)
				(justify mirror)
			)
		)
		(duplicate_pad_numbers_are_jumpers no)
		(fp_line
			(start -0.7874 -0.4064)
			(end -0.7874 0.4064)
			(stroke
				(width 0.1524)
				(type default)
			)
			(layer "B.SilkS")
		)
		(fp_line
			(start -0.7874 0.4064)
			(end 0.7874 0.4064)
			(stroke
				(width 0.1524)
				(type default)
			)
			(layer "B.SilkS")
		)
		(fp_line
			(start 0.7874 -0.4064)
			(end -0.7874 -0.4064)
			(stroke
				(width 0.1524)
				(type default)
			)
			(layer "B.SilkS")
		)
		(fp_line
			(start 0.7874 0.4064)
			(end 0.7874 -0.4064)
			(stroke
				(width 0.1524)
				(type default)
			)
			(layer "B.SilkS")
		)
		(fp_line
			(start -0.67945 -0.3048)
			(end -0.67945 0.3048)
			(stroke
				(width 0.1)
				(type default)
			)
			(layer "B.Fab")
		)
		(fp_line
			(start -0.67945 0.3048)
			(end -0.120396 0.3048)
			(stroke
				(width 0.1)
				(type default)
			)
			(layer "B.Fab")
		)
		(fp_line
			(start -0.12065 -0.3048)
			(end -0.67945 -0.3048)
			(stroke
				(width 0.1)
				(type default)
			)
			(layer "B.Fab")
		)
		(fp_line
			(start -0.12065 -0.2794)
			(end -0.12065 -0.3048)
			(stroke
				(width 0.1)
				(type default)
			)
			(layer "B.Fab")
		)
		(fp_line
			(start -0.120396 0.2794)
			(end 0.12065 0.2794)
			(stroke
				(width 0.1)
				(type default)
			)
			(layer "B.Fab")
		)
		(fp_line
			(start -0.120396 0.3048)
			(end -0.120396 0.2794)
			(stroke
				(width 0.1)
				(type default)
			)
			(layer "B.Fab")
		)
		(fp_line
			(start 0.12065 -0.305054)
			(end 0.12065 -0.2794)
			(stroke
				(width 0.1)
				(type default)
			)
			(layer "B.Fab")
		)
		(fp_line
			(start 0.12065 -0.2794)
			(end -0.12065 -0.2794)
			(stroke
				(width 0.1)
				(type default)
			)
			(layer "B.Fab")
		)
		(fp_line
			(start 0.12065 0.2794)
			(end 0.12065 0.3048)
			(stroke
				(width 0.1)
				(type default)
			)
			(layer "B.Fab")
		)
		(fp_line
			(start 0.12065 0.3048)
			(end 0.67945 0.3048)
			(stroke
				(width 0.1)
				(type default)
			)
			(layer "B.Fab")
		)
		(fp_line
			(start 0.67945 -0.305054)
			(end 0.12065 -0.305054)
			(stroke
				(width 0.1)
				(type default)
			)
			(layer "B.Fab")
		)
		(fp_line
			(start 0.67945 0.3048)
			(end 0.67945 -0.305054)
			(stroke
				(width 0.1)
				(type default)
			)
			(layer "B.Fab")
		)
		(pad "1" smd circle
			(at 0.40005 0 180)
			(size 0 0)
			(layers "B.Cu" "B.Mask" "B.Paste")
			(net "GND")
		)
		(pad "2" smd circle
			(at -0.40005 0 180)
			(size 0 0)
			(layers "B.Cu" "B.Mask" "B.Paste")
			(net "CPU0_PWR_GD_OUT")
		)
	)
	(footprint ""
		(layer "B.Cu")
		(at 157.136846 -408.517344 90)
		(property "Reference" "C6751"
			(at 0 0 90)
			(layer "B.SilkS")
			(hide yes)
			(effects
				(font
					(size 1.27 1.27)
				)
				(justify mirror)
			)
		)
		(property "Value" ""
			(at 0 0 90)
			(layer "B.Fab")
			(effects
				(font
					(size 1.27 1.27)
				)
				(justify mirror)
			)
		)
		(duplicate_pad_numbers_are_jumpers no)
		(fp_line
			(start 0.299974 -0.150114)
			(end -0.299974 -0.150114)
			(stroke
				(width 0.1)
				(type default)
			)
			(layer "B.Fab")
		)
		(fp_line
			(start -0.299974 -0.150114)
			(end -0.299974 0.150114)
			(stroke
				(width 0.1)
				(type default)
			)
			(layer "B.Fab")
		)
		(fp_line
			(start 0.299974 0.150114)
			(end 0.299974 -0.150114)
			(stroke
				(width 0.1)
				(type default)
			)
			(layer "B.Fab")
		)
		(fp_line
			(start -0.299974 0.150114)
			(end 0.299974 0.150114)
			(stroke
				(width 0.1)
				(type default)
			)
			(layer "B.Fab")
		)
		(pad "1" smd rect
			(at 0.2667 0 270)
			(size 0.3048 0.381)
			(layers "B.Cu" "B.Mask" "B.Paste")
			(net "P5E_CPU1_P3_TX_BUF_C_DP<13>")
		)
		(pad "2" smd rect
			(at -0.2667 0 270)
			(size 0.3048 0.381)
			(layers "B.Cu" "B.Mask" "B.Paste")
			(net "P5E_CPU1_P3_TX_BUF_DP<13>")
		)
	)
	(footprint ""
		(layer "B.Cu")
		(at 233.68 -331.724 180)
		(property "Reference" "R6784"
			(at 0 0 0)
			(layer "B.SilkS")
			(hide yes)
			(effects
				(font
					(size 1.27 1.27)
				)
				(justify mirror)
			)
		)
		(property "Value" ""
			(at 0 0 0)
			(layer "B.Fab")
			(effects
				(font
					(size 1.27 1.27)
				)
				(justify mirror)
			)
		)
		(duplicate_pad_numbers_are_jumpers no)
		(fp_line
			(start 0.7874 0.4064)
			(end 0.7874 -0.4064)
			(stroke
				(width 0.1524)
				(type default)
			)
			(layer "B.SilkS")
		)
		(fp_line
			(start 0.7874 -0.4064)
			(end -0.7874 -0.4064)
			(stroke
				(width 0.1524)
				(type default)
			)
			(layer "B.SilkS")
		)
		(fp_line
			(start -0.7874 0.4064)
			(end 0.7874 0.4064)
			(stroke
				(width 0.1524)
				(type default)
			)
			(layer "B.SilkS")
		)
		(fp_line
			(start -0.7874 -0.4064)
			(end -0.7874 0.4064)
			(stroke
				(width 0.1524)
				(type default)
			)
			(layer "B.SilkS")
		)
		(fp_line
			(start 0.67945 0.3048)
			(end 0.67945 -0.305054)
			(stroke
				(width 0.1)
				(type default)
			)
			(layer "B.Fab")
		)
		(fp_line
			(start 0.67945 -0.305054)
			(end 0.12065 -0.305054)
			(stroke
				(width 0.1)
				(type default)
			)
			(layer "B.Fab")
		)
		(fp_line
			(start 0.12065 0.3048)
			(end 0.67945 0.3048)
			(stroke
				(width 0.1)
				(type default)
			)
			(layer "B.Fab")
		)
		(fp_line
			(start 0.12065 0.2794)
			(end 0.12065 0.3048)
			(stroke
				(width 0.1)
				(type default)
			)
			(layer "B.Fab")
		)
		(fp_line
			(start 0.12065 -0.2794)
			(end -0.12065 -0.2794)
			(stroke
				(width 0.1)
				(type default)
			)
			(layer "B.Fab")
		)
		(fp_line
			(start 0.12065 -0.305054)
			(end 0.12065 -0.2794)
			(stroke
				(width 0.1)
				(type default)
			)
			(layer "B.Fab")
		)
		(fp_line
			(start -0.120396 0.3048)
			(end -0.120396 0.2794)
			(stroke
				(width 0.1)
				(type default)
			)
			(layer "B.Fab")
		)
		(fp_line
			(start -0.120396 0.2794)
			(end 0.12065 0.2794)
			(stroke
				(width 0.1)
				(type default)
			)
			(layer "B.Fab")
		)
		(fp_line
			(start -0.12065 -0.2794)
			(end -0.12065 -0.3048)
			(stroke
				(width 0.1)
				(type default)
			)
			(layer "B.Fab")
		)
		(fp_line
			(start -0.12065 -0.3048)
			(end -0.67945 -0.3048)
			(stroke
				(width 0.1)
				(type default)
			)
			(layer "B.Fab")
		)
		(fp_line
			(start -0.67945 0.3048)
			(end -0.120396 0.3048)
			(stroke
				(width 0.1)
				(type default)
			)
			(layer "B.Fab")
		)
		(fp_line
			(start -0.67945 -0.3048)
			(end -0.67945 0.3048)
			(stroke
				(width 0.1)
				(type default)
			)
			(layer "B.Fab")
		)
		(pad "1" smd circle
			(at 0.40005 0)
			(size 0 0)
			(layers "B.Cu" "B.Mask" "B.Paste")
			(net "SMB_MUX_RT_R1_SCL")
		)
		(pad "2" smd circle
			(at -0.40005 0)
			(size 0 0)
			(layers "B.Cu" "B.Mask" "B.Paste")
			(net "SMB_SML1_PMBUS_HSC_SCL")
		)
	)
	(footprint ""
		(layer "B.Cu")
		(at 102.401878 -146.66341)
		(property "Reference" "PR174"
			(at 0 0 0)
			(layer "B.SilkS")
			(hide yes)
			(effects
				(font
					(size 1.27 1.27)
				)
				(justify mirror)
			)
		)
		(property "Value" ""
			(at 0 0 0)
			(layer "B.Fab")
			(effects
				(font
					(size 1.27 1.27)
				)
				(justify mirror)
			)
		)
		(duplicate_pad_numbers_are_jumpers no)
		(fp_line
			(start -0.7874 -0.4064)
			(end -0.7874 0.4064)
			(stroke
				(width 0.1524)
				(type default)
			)
			(layer "B.SilkS")
		)
		(fp_line
			(start -0.7874 0.4064)
			(end 0.7874 0.4064)
			(stroke
				(width 0.1524)
				(type default)
			)
			(layer "B.SilkS")
		)
		(fp_line
			(start 0.7874 -0.4064)
			(end -0.7874 -0.4064)
			(stroke
				(width 0.1524)
				(type default)
			)
			(layer "B.SilkS")
		)
		(fp_line
			(start 0.7874 0.4064)
			(end 0.7874 -0.4064)
			(stroke
				(width 0.1524)
				(type default)
			)
			(layer "B.SilkS")
		)
		(fp_line
			(start -0.67945 -0.3048)
			(end -0.67945 0.3048)
			(stroke
				(width 0.1)
				(type default)
			)
			(layer "B.Fab")
		)
		(fp_line
			(start -0.67945 0.3048)
			(end -0.120396 0.3048)
			(stroke
				(width 0.1)
				(type default)
			)
			(layer "B.Fab")
		)
		(fp_line
			(start -0.12065 -0.3048)
			(end -0.67945 -0.3048)
			(stroke
				(width 0.1)
				(type default)
			)
			(layer "B.Fab")
		)
		(fp_line
			(start -0.12065 -0.2794)
			(end -0.12065 -0.3048)
			(stroke
				(width 0.1)
				(type default)
			)
			(layer "B.Fab")
		)
		(fp_line
			(start -0.120396 0.2794)
			(end 0.12065 0.2794)
			(stroke
				(width 0.1)
				(type default)
			)
			(layer "B.Fab")
		)
		(fp_line
			(start -0.120396 0.3048)
			(end -0.120396 0.2794)
			(stroke
				(width 0.1)
				(type default)
			)
			(layer "B.Fab")
		)
		(fp_line
			(start 0.12065 -0.305054)
			(end 0.12065 -0.2794)
			(stroke
				(width 0.1)
				(type default)
			)
			(layer "B.Fab")
		)
		(fp_line
			(start 0.12065 -0.2794)
			(end -0.12065 -0.2794)
			(stroke
				(width 0.1)
				(type default)
			)
			(layer "B.Fab")
		)
		(fp_line
			(start 0.12065 0.2794)
			(end 0.12065 0.3048)
			(stroke
				(width 0.1)
				(type default)
			)
			(layer "B.Fab")
		)
		(fp_line
			(start 0.12065 0.3048)
			(end 0.67945 0.3048)
			(stroke
				(width 0.1)
				(type default)
			)
			(layer "B.Fab")
		)
		(fp_line
			(start 0.67945 -0.305054)
			(end 0.12065 -0.305054)
			(stroke
				(width 0.1)
				(type default)
			)
			(layer "B.Fab")
		)
		(fp_line
			(start 0.67945 0.3048)
			(end 0.67945 -0.305054)
			(stroke
				(width 0.1)
				(type default)
			)
			(layer "B.Fab")
		)
		(pad "1" smd circle
			(at 0.40005 0 180)
			(size 0 0)
			(layers "B.Cu" "B.Mask" "B.Paste")
			(net "VSENSE_PVDDCR_SOC_P1_DP")
		)
		(pad "2" smd circle
			(at -0.40005 0 180)
			(size 0 0)
			(layers "B.Cu" "B.Mask" "B.Paste")
			(net "VSENSE_PVDDCR_SOC_P1_VSEN1")
		)
	)
	(footprint ""
		(layer "B.Cu")
		(at 323.386958 -199.980296)
		(property "Reference" "R452"
			(at 0 0 0)
			(layer "B.SilkS")
			(hide yes)
			(effects
				(font
					(size 1.27 1.27)
				)
				(justify mirror)
			)
		)
		(property "Value" ""
			(at 0 0 0)
			(layer "B.Fab")
			(effects
				(font
					(size 1.27 1.27)
				)
				(justify mirror)
			)
		)
		(duplicate_pad_numbers_are_jumpers no)
		(fp_line
			(start -0.7874 -0.4064)
			(end -0.7874 0.4064)
			(stroke
				(width 0.1524)
				(type default)
			)
			(layer "B.SilkS")
		)
		(fp_line
			(start -0.7874 0.4064)
			(end 0.7874 0.4064)
			(stroke
				(width 0.1524)
				(type default)
			)
			(layer "B.SilkS")
		)
		(fp_line
			(start 0.7874 -0.4064)
			(end -0.7874 -0.4064)
			(stroke
				(width 0.1524)
				(type default)
			)
			(layer "B.SilkS")
		)
		(fp_line
			(start 0.7874 0.4064)
			(end 0.7874 -0.4064)
			(stroke
				(width 0.1524)
				(type default)
			)
			(layer "B.SilkS")
		)
		(fp_line
			(start -0.67945 -0.3048)
			(end -0.67945 0.3048)
			(stroke
				(width 0.1)
				(type default)
			)
			(layer "B.Fab")
		)
		(fp_line
			(start -0.67945 0.3048)
			(end -0.120396 0.3048)
			(stroke
				(width 0.1)
				(type default)
			)
			(layer "B.Fab")
		)
		(fp_line
			(start -0.12065 -0.3048)
			(end -0.67945 -0.3048)
			(stroke
				(width 0.1)
				(type default)
			)
			(layer "B.Fab")
		)
		(fp_line
			(start -0.12065 -0.2794)
			(end -0.12065 -0.3048)
			(stroke
				(width 0.1)
				(type default)
			)
			(layer "B.Fab")
		)
		(fp_line
			(start -0.120396 0.2794)
			(end 0.12065 0.2794)
			(stroke
				(width 0.1)
				(type default)
			)
			(layer "B.Fab")
		)
		(fp_line
			(start -0.120396 0.3048)
			(end -0.120396 0.2794)
			(stroke
				(width 0.1)
				(type default)
			)
			(layer "B.Fab")
		)
		(fp_line
			(start 0.12065 -0.305054)
			(end 0.12065 -0.2794)
			(stroke
				(width 0.1)
				(type default)
			)
			(layer "B.Fab")
		)
		(fp_line
			(start 0.12065 -0.2794)
			(end -0.12065 -0.2794)
			(stroke
				(width 0.1)
				(type default)
			)
			(layer "B.Fab")
		)
		(fp_line
			(start 0.12065 0.2794)
			(end 0.12065 0.3048)
			(stroke
				(width 0.1)
				(type default)
			)
			(layer "B.Fab")
		)
		(fp_line
			(start 0.12065 0.3048)
			(end 0.67945 0.3048)
			(stroke
				(width 0.1)
				(type default)
			)
			(layer "B.Fab")
		)
		(fp_line
			(start 0.67945 -0.305054)
			(end 0.12065 -0.305054)
			(stroke
				(width 0.1)
				(type default)
			)
			(layer "B.Fab")
		)
		(fp_line
			(start 0.67945 0.3048)
			(end 0.67945 -0.305054)
			(stroke
				(width 0.1)
				(type default)
			)
			(layer "B.Fab")
		)
		(pad "1" smd circle
			(at 0.40005 0 180)
			(size 0 0)
			(layers "B.Cu" "B.Mask" "B.Paste")
			(net "CPU0_NV_SAVE_N")
		)
		(pad "2" smd circle
			(at -0.40005 0 180)
			(size 0 0)
			(layers "B.Cu" "B.Mask" "B.Paste")
			(net "PVDD18_S5_P0")
		)
	)
)
